# T6G (Grand Teton) — schematic netlist excerpt (pin names and nets, part order shuffled) for the footprints in the layout excerpt that follows; sources: Cadence DE-HDL packaged netlist, KiCad conversion of 04192023_DAF0TMB3IC0_F0TG_MB_C_brd_V02_OCP.brd

R336  Q_RES  100K 1% CHIP  pkg 0402LF  page 188 : A = P12V_AUX ; B = VR_P5V_EN_N

(kicad_pcb
	(version 20260206)
	(generator "pcbnew")
	(generator_version "10.0")
	(general
		(thickness 1.6)
		(legacy_teardrops no)
	)
	(paper "A4")
	(title_block
		(title "04192023_DAF0TMB3IC0_F0TG_MB_C_brd_V02_OCP.brd")
		(comment 1 "Grand Teton / footprints 2099-2099 of 8354")
	)
	(layers
		(0 "F.Cu" signal "TOP")
		(4 "In1.Cu" signal "GND")
		(6 "In2.Cu" signal "IN1")
		(8 "In3.Cu" signal "GND1")
		(10 "In4.Cu" signal "IN2")
		(12 "In5.Cu" signal "GND2")
		(14 "In6.Cu" signal "IN3")
		(16 "In7.Cu" signal "GND3")
		(18 "In8.Cu" signal "VCC")
		(20 "In9.Cu" signal "VCC1")
		(22 "In10.Cu" signal "GND4")
		(24 "In11.Cu" signal "IN4")
		(26 "In12.Cu" signal "GND5")
		(28 "In13.Cu" signal "IN5")
		(30 "In14.Cu" signal "GND6")
		(32 "In15.Cu" signal "IN6")
		(34 "In16.Cu" signal "GND7")
		(2 "B.Cu" signal "BOTTOM")
		(9 "F.Adhes" user "F.Adhesive")
		(11 "B.Adhes" user "B.Adhesive")
		(13 "F.Paste" user "Package Geometry/Pastemask Top")
		(15 "B.Paste" user "Package Geometry/Pastemask Bottom")
		(5 "F.SilkS" user "Ref Des/Silkscreen Top")
		(7 "B.SilkS" user "Ref Des/Silkscreen Bottom")
		(1 "F.Mask" user "Board Geometry/Soldermask Top")
		(3 "B.Mask" user "Board Geometry/Soldermask Bottom")
		(17 "Dwgs.User" user "User.Drawings")
		(19 "Cmts.User" user "User.Comments")
		(21 "Eco1.User" user "User.Eco1")
		(23 "Eco2.User" user "User.Eco2")
		(25 "Edge.Cuts" user "Board Geometry/Outline")
		(27 "Margin" user)
		(31 "F.CrtYd" user "Package Geometry/Place Bound Top")
		(29 "B.CrtYd" user "Package Geometry/Place Bound Bottom")
		(35 "F.Fab" user "Ref Des/Assembly Top")
		(33 "B.Fab" user "Ref Des/Assembly Bottom")
	)
	(footprint ""
		(layer "F.Cu")
		(at 140.886942 -107.683046)
		(property "Reference" "R336"
			(at 0 0 0)
			(layer "F.SilkS")
			(hide yes)
			(effects
				(font
					(size 1.27 1.27)
				)
			)
		)
		(property "Value" ""
			(at 0 0 0)
			(layer "F.Fab")
			(effects
				(font
					(size 1.27 1.27)
				)
			)
		)
		(duplicate_pad_numbers_are_jumpers no)
		(fp_line
			(start -0.7874 -0.4064)
			(end 0.7874 -0.4064)
			(stroke
				(width 0.1524)
				(type default)
			)
			(layer "F.SilkS")
		)
		(fp_line
			(start -0.7874 0.4064)
			(end -0.7874 -0.4064)
			(stroke
				(width 0.1524)
				(type default)
			)
			(layer "F.SilkS")
		)
		(fp_line
			(start 0.7874 -0.4064)
			(end 0.7874 0.4064)
			(stroke
				(width 0.1524)
				(type default)
			)
			(layer "F.SilkS")
		)
		(fp_line
			(start 0.7874 0.4064)
			(end -0.7874 0.4064)
			(stroke
				(width 0.1524)
				(type default)
			)
			(layer "F.SilkS")
		)
		(fp_line
			(start -0.67945 -0.305054)
			(end -0.12065 -0.305054)
			(stroke
				(width 0.1)
				(type default)
			)
			(layer "F.Fab")
		)
		(fp_line
			(start -0.67945 0.3048)
			(end -0.67945 -0.305054)
			(stroke
				(width 0.1)
				(type default)
			)
			(layer "F.Fab")
		)
		(fp_line
			(start -0.12065 -0.305054)
			(end -0.12065 -0.2794)
			(stroke
				(width 0.1)
				(type default)
			)
			(layer "F.Fab")
		)
		(fp_line
			(start -0.12065 -0.2794)
			(end 0.12065 -0.2794)
			(stroke
				(width 0.1)
				(type default)
			)
			(layer "F.Fab")
		)
		(fp_line
			(start -0.12065 0.2794)
			(end -0.12065 0.3048)
			(stroke
				(width 0.1)
				(type default)
			)
			(layer "F.Fab")
		)
		(fp_line
			(start -0.12065 0.3048)
			(end -0.67945 0.3048)
			(stroke
				(width 0.1)
				(type default)
			)
			(layer "F.Fab")
		)
		(fp_line
			(start 0.120396 0.2794)
			(end -0.12065 0.2794)
			(stroke
				(width 0.1)
				(type default)
			)
			(layer "F.Fab")
		)
		(fp_line
			(start 0.120396 0.3048)
			(end 0.120396 0.2794)
			(stroke
				(width 0.1)
				(type default)
			)
			(layer "F.Fab")
		)
		(fp_line
			(start 0.12065 -0.3048)
			(end 0.67945 -0.3048)
			(stroke
				(width 0.1)
				(type default)
			)
			(layer "F.Fab")
		)
		(fp_line
			(start 0.12065 -0.2794)
			(end 0.12065 -0.3048)
			(stroke
				(width 0.1)
				(type default)
			)
			(layer "F.Fab")
		)
		(fp_line
			(start 0.67945 -0.3048)
			(end 0.67945 0.3048)
			(stroke
				(width 0.1)
				(type default)
			)
			(layer "F.Fab")
		)
		(fp_line
			(start 0.67945 0.3048)
			(end 0.120396 0.3048)
			(stroke
				(width 0.1)
				(type default)
			)
			(layer "F.Fab")
		)
		(pad "1" smd circle
			(at -0.40005 0)
			(size 0 0)
			(layers "F.Cu" "F.Mask" "F.Paste")
			(net "P12V_AUX")
		)
		(pad "2" smd circle
			(at 0.40005 0)
			(size 0 0)
			(layers "F.Cu" "F.Mask" "F.Paste")
			(net "VR_P5V_EN_N")
		)
	)
)
